# T6G (Grand Teton) — schematic netlist excerpt (pin names and nets, part order shuffled) for the footprints in the layout excerpt that follows; sources: Cadence DE-HDL packaged netlist, KiCad conversion of 04192023_DAF0TMB3IC0_F0TG_MB_C_brd_V02_OCP.brd

C3929  Q_CAP  22UF 4V 20% X6S  pkg C0402  page 70 : A = PVDDCR_SOC_P0 ; B = GND

PL43  Q_INDUCTOR4P_14  150NH IND  pkg L_TLM117513Q-151QL_11X7-5XA  page 219
  \1\  = SW_PVDDCR_CPU1_P1_SW4
  \2\  = IND_CPU1_P1_CPL3
  \3\  = GND
  \4\  = PVDDCR_CPU1_P1

C737  Q_CAP_DIFFBUS  DIFF BUS_0.22UF 6.3V 20% X6S  pkg C0201  page 66 : \1\ = P5E_CPU1_P1_TX_C_DP<2> ; \2\ = P5E_CPU1_P1_TX_DP<2>

(kicad_pcb
	(version 20260206)
	(generator "pcbnew")
	(generator_version "10.0")
	(general
		(thickness 1.6)
		(legacy_teardrops no)
	)
	(paper "A4")
	(title_block
		(title "04192023_DAF0TMB3IC0_F0TG_MB_C_brd_V02_OCP.brd")
		(comment 1 "Grand Teton / footprints 2309-2311 of 8354")
	)
	(layers
		(0 "F.Cu" signal "TOP")
		(4 "In1.Cu" signal "GND")
		(6 "In2.Cu" signal "IN1")
		(8 "In3.Cu" signal "GND1")
		(10 "In4.Cu" signal "IN2")
		(12 "In5.Cu" signal "GND2")
		(14 "In6.Cu" signal "IN3")
		(16 "In7.Cu" signal "GND3")
		(18 "In8.Cu" signal "VCC")
		(20 "In9.Cu" signal "VCC1")
		(22 "In10.Cu" signal "GND4")
		(24 "In11.Cu" signal "IN4")
		(26 "In12.Cu" signal "GND5")
		(28 "In13.Cu" signal "IN5")
		(30 "In14.Cu" signal "GND6")
		(32 "In15.Cu" signal "IN6")
		(34 "In16.Cu" signal "GND7")
		(2 "B.Cu" signal "BOTTOM")
		(9 "F.Adhes" user "F.Adhesive")
		(11 "B.Adhes" user "B.Adhesive")
		(13 "F.Paste" user "Package Geometry/Pastemask Top")
		(15 "B.Paste" user "Package Geometry/Pastemask Bottom")
		(5 "F.SilkS" user "Ref Des/Silkscreen Top")
		(7 "B.SilkS" user "Ref Des/Silkscreen Bottom")
		(1 "F.Mask" user "Board Geometry/Soldermask Top")
		(3 "B.Mask" user "Board Geometry/Soldermask Bottom")
		(17 "Dwgs.User" user "User.Drawings")
		(19 "Cmts.User" user "User.Comments")
		(21 "Eco1.User" user "User.Eco1")
		(23 "Eco2.User" user "User.Eco2")
		(25 "Edge.Cuts" user "Board Geometry/Outline")
		(27 "Margin" user)
		(31 "F.CrtYd" user "Package Geometry/Place Bound Top")
		(29 "B.CrtYd" user "Package Geometry/Place Bound Bottom")
		(35 "F.Fab" user "Ref Des/Assembly Top")
		(33 "B.Fab" user "Ref Des/Assembly Bottom")
	)
	(footprint ""
		(layer "F.Cu")
		(at 359.416096 -256.012188 90)
		(property "Reference" "C3929"
			(at 0 0 90)
			(layer "F.SilkS")
			(hide yes)
			(effects
				(font
					(size 1.27 1.27)
				)
			)
		)
		(property "Value" ""
			(at 0 0 90)
			(layer "F.Fab")
			(effects
				(font
					(size 1.27 1.27)
				)
			)
		)
		(duplicate_pad_numbers_are_jumpers no)
		(fp_line
			(start 0.7874 -0.4064)
			(end 0.7874 0.4064)
			(stroke
				(width 0.1524)
				(type default)
			)
			(layer "F.SilkS")
		)
		(fp_line
			(start -0.7874 -0.4064)
			(end 0.7874 -0.4064)
			(stroke
				(width 0.1524)
				(type default)
			)
			(layer "F.SilkS")
		)
		(fp_line
			(start 0.7874 0.4064)
			(end -0.7874 0.4064)
			(stroke
				(width 0.1524)
				(type default)
			)
			(layer "F.SilkS")
		)
		(fp_line
			(start -0.7874 0.4064)
			(end -0.7874 -0.4064)
			(stroke
				(width 0.1524)
				(type default)
			)
			(layer "F.SilkS")
		)
		(fp_line
			(start -0.12065 -0.305054)
			(end -0.12065 -0.2794)
			(stroke
				(width 0.1)
				(type default)
			)
			(layer "F.Fab")
		)
		(fp_line
			(start -0.67945 -0.305054)
			(end -0.12065 -0.305054)
			(stroke
				(width 0.1)
				(type default)
			)
			(layer "F.Fab")
		)
		(fp_line
			(start 0.67945 -0.3048)
			(end 0.67945 0.3048)
			(stroke
				(width 0.1)
				(type default)
			)
			(layer "F.Fab")
		)
		(fp_line
			(start 0.12065 -0.3048)
			(end 0.67945 -0.3048)
			(stroke
				(width 0.1)
				(type default)
			)
			(layer "F.Fab")
		)
		(fp_line
			(start 0.12065 -0.2794)
			(end 0.12065 -0.3048)
			(stroke
				(width 0.1)
				(type default)
			)
			(layer "F.Fab")
		)
		(fp_line
			(start -0.12065 -0.2794)
			(end 0.12065 -0.2794)
			(stroke
				(width 0.1)
				(type default)
			)
			(layer "F.Fab")
		)
		(fp_line
			(start 0.120396 0.2794)
			(end -0.12065 0.2794)
			(stroke
				(width 0.1)
				(type default)
			)
			(layer "F.Fab")
		)
		(fp_line
			(start -0.12065 0.2794)
			(end -0.12065 0.3048)
			(stroke
				(width 0.1)
				(type default)
			)
			(layer "F.Fab")
		)
		(fp_line
			(start 0.67945 0.3048)
			(end 0.120396 0.3048)
			(stroke
				(width 0.1)
				(type default)
			)
			(layer "F.Fab")
		)
		(fp_line
			(start 0.120396 0.3048)
			(end 0.120396 0.2794)
			(stroke
				(width 0.1)
				(type default)
			)
			(layer "F.Fab")
		)
		(fp_line
			(start -0.12065 0.3048)
			(end -0.67945 0.3048)
			(stroke
				(width 0.1)
				(type default)
			)
			(layer "F.Fab")
		)
		(fp_line
			(start -0.67945 0.3048)
			(end -0.67945 -0.305054)
			(stroke
				(width 0.1)
				(type default)
			)
			(layer "F.Fab")
		)
		(pad "1" smd circle
			(at -0.40005 0 90)
			(size 0 0)
			(layers "F.Cu" "F.Mask" "F.Paste")
			(net "PVDDCR_SOC_P0")
		)
		(pad "2" smd circle
			(at 0.40005 0 90)
			(size 0 0)
			(layers "F.Cu" "F.Mask" "F.Paste")
			(net "GND")
		)
	)
	(footprint ""
		(layer "F.Cu")
		(at 75.517502 -373.03583 -90)
		(property "Reference" "C737"
			(at 0 0 270)
			(layer "F.SilkS")
			(hide yes)
			(effects
				(font
					(size 1.27 1.27)
				)
			)
		)
		(property "Value" ""
			(at 0 0 270)
			(layer "F.Fab")
			(effects
				(font
					(size 1.27 1.27)
				)
			)
		)
		(duplicate_pad_numbers_are_jumpers no)
		(fp_line
			(start -0.299974 0.150114)
			(end -0.299974 -0.150114)
			(stroke
				(width 0.1)
				(type default)
			)
			(layer "F.Fab")
		)
		(fp_line
			(start 0.299974 0.150114)
			(end -0.299974 0.150114)
			(stroke
				(width 0.1)
				(type default)
			)
			(layer "F.Fab")
		)
		(fp_line
			(start -0.299974 -0.150114)
			(end 0.299974 -0.150114)
			(stroke
				(width 0.1)
				(type default)
			)
			(layer "F.Fab")
		)
		(fp_line
			(start 0.299974 -0.150114)
			(end 0.299974 0.150114)
			(stroke
				(width 0.1)
				(type default)
			)
			(layer "F.Fab")
		)
		(pad "1" smd rect
			(at -0.2667 0 270)
			(size 0.3048 0.381)
			(layers "F.Cu" "F.Mask" "F.Paste")
			(net "P5E_CPU1_P1_TX_C_DP<2>")
		)
		(pad "2" smd rect
			(at 0.2667 0 270)
			(size 0.3048 0.381)
			(layers "F.Cu" "F.Mask" "F.Paste")
			(net "P5E_CPU1_P1_TX_DP<2>")
		)
	)
	(footprint ""
		(layer "F.Cu")
		(at 61.81471 -337.403948)
		(property "Reference" "PL43"
			(at -3.115056 -15.633446 0)
			(unlocked yes)
			(layer "F.SilkS")
			(effects
				(font
					(size 0.7874 0.5842)
					(thickness 0.1524)
				)
				(justify left)
			)
		)
		(property "Value" ""
			(at 0 0 0)
			(layer "F.Fab")
			(effects
				(font
					(size 1.27 1.27)
				)
			)
		)
		(duplicate_pad_numbers_are_jumpers no)
		(fp_line
			(start -3.750056 -5.500116)
			(end -2.393442 -5.500116)
			(stroke
				(width 0.1524)
				(type default)
			)
			(layer "F.SilkS")
		)
		(fp_line
			(start -3.750056 5.500116)
			(end -3.750056 -5.500116)
			(stroke
				(width 0.1524)
				(type default)
			)
			(layer "F.SilkS")
		)
		(fp_line
			(start -2.393442 5.500116)
			(end -3.750056 5.500116)
			(stroke
				(width 0.1524)
				(type default)
			)
			(layer "F.SilkS")
		)
		(fp_line
			(start 2.393442 5.500116)
			(end 3.750056 5.500116)
			(stroke
				(width 0.1524)
				(type default)
			)
			(layer "F.SilkS")
		)
		(fp_line
			(start 3.750056 -5.500116)
			(end 2.393442 -5.500116)
			(stroke
				(width 0.1524)
				(type default)
			)
			(layer "F.SilkS")
		)
		(fp_line
			(start 3.750056 5.500116)
			(end 3.750056 -5.500116)
			(stroke
				(width 0.1524)
				(type default)
			)
			(layer "F.SilkS")
		)
		(fp_poly
			(pts
				(xy -3.9116 -4.249928) (xy -4.3434 -4.034028) (xy -4.3434 -4.465828)
			)
			(stroke
				(width 0)
				(type default)
			)
			(fill yes)
			(layer "F.SilkS")
		)
		(fp_line
			(start -3.750056 -5.500116)
			(end -3.750056 5.500116)
			(stroke
				(width 0.1)
				(type default)
			)
			(layer "F.Fab")
		)
		(fp_line
			(start -3.750056 5.500116)
			(end 3.750056 5.500116)
			(stroke
				(width 0.1)
				(type default)
			)
			(layer "F.Fab")
		)
		(fp_line
			(start 3.750056 -5.500116)
			(end -3.750056 -5.500116)
			(stroke
				(width 0.1)
				(type default)
			)
			(layer "F.Fab")
		)
		(fp_line
			(start 3.750056 5.500116)
			(end 3.750056 -5.500116)
			(stroke
				(width 0.1)
				(type default)
			)
			(layer "F.Fab")
		)
		(fp_poly
			(pts
				(xy -4.9276 -4.757928) (xy -4.9276 -3.741928) (xy -3.9116 -4.249928)
			)
			(stroke
				(width 0)
				(type default)
			)
			(fill yes)
			(layer "F.Fab")
		)
		(pad "1" smd rect
			(at 0 -4.249928 270)
			(size 2.413 4.5212)
			(layers "F.Cu" "F.Mask" "F.Paste")
			(net "SW_PVDDCR_CPU1_P1_SW4")
		)
		(pad "2" smd rect
			(at 0 -1.175004 270)
			(size 1.3716 4.5212)
			(layers "F.Cu" "F.Mask" "F.Paste")
			(net "IND_CPU1_P1_CPL3")
		)
		(pad "3" smd rect
			(at 0 1.175004 270)
			(size 1.3716 4.5212)
			(layers "F.Cu" "F.Mask" "F.Paste")
			(net "GND")
		)
		(pad "4" smd rect
			(at 0 4.249928 270)
			(size 2.413 4.5212)
			(layers "F.Cu" "F.Mask" "F.Paste")
			(net "PVDDCR_CPU1_P1")
		)
	)
)
